# T6G (Grand Teton) — schematic netlist excerpt (pin names and nets, part order shuffled) for the footprints in the layout excerpt that follows; sources: Cadence DE-HDL packaged netlist, KiCad conversion of 04192023_DAF0TMB3IC0_F0TG_MB_C_brd_V02_OCP.brd

C7001  Q_CAPP  470UF 2.5V 20% SPCAP  pkg SMLF  page 279 : A = P0V9_CPU0_RT_2D ; B = GND
C2503  Q_CAP  22UF 4V 20% X6S  pkg C0402  page 74 : A = PVDD11_S3_P1 ; B = GND
C6514  Q_CAP_DIFFBUS  DIFF BUS_0.22UF 6.3V 20% X6S  pkg C0201  page 275 : \1\ = P5E_CPU0_P0_TX_BUF_C_DN<6> ; \2\ = P5E_CPU0_P0_TX_BUF_DN<6>

(kicad_pcb
	(version 20260206)
	(generator "pcbnew")
	(generator_version "10.0")
	(general
		(thickness 1.6)
		(legacy_teardrops no)
	)
	(paper "A4")
	(title_block
		(title "04192023_DAF0TMB3IC0_F0TG_MB_C_brd_V02_OCP.brd")
		(comment 1 "Grand Teton / footprints 612-614 of 8354")
	)
	(layers
		(0 "F.Cu" signal "TOP")
		(4 "In1.Cu" signal "GND")
		(6 "In2.Cu" signal "IN1")
		(8 "In3.Cu" signal "GND1")
		(10 "In4.Cu" signal "IN2")
		(12 "In5.Cu" signal "GND2")
		(14 "In6.Cu" signal "IN3")
		(16 "In7.Cu" signal "GND3")
		(18 "In8.Cu" signal "VCC")
		(20 "In9.Cu" signal "VCC1")
		(22 "In10.Cu" signal "GND4")
		(24 "In11.Cu" signal "IN4")
		(26 "In12.Cu" signal "GND5")
		(28 "In13.Cu" signal "IN5")
		(30 "In14.Cu" signal "GND6")
		(32 "In15.Cu" signal "IN6")
		(34 "In16.Cu" signal "GND7")
		(2 "B.Cu" signal "BOTTOM")
		(9 "F.Adhes" user "F.Adhesive")
		(11 "B.Adhes" user "B.Adhesive")
		(13 "F.Paste" user "Package Geometry/Pastemask Top")
		(15 "B.Paste" user "Package Geometry/Pastemask Bottom")
		(5 "F.SilkS" user "Ref Des/Silkscreen Top")
		(7 "B.SilkS" user "Ref Des/Silkscreen Bottom")
		(1 "F.Mask" user "Board Geometry/Soldermask Top")
		(3 "B.Mask" user "Board Geometry/Soldermask Bottom")
		(17 "Dwgs.User" user "User.Drawings")
		(19 "Cmts.User" user "User.Comments")
		(21 "Eco1.User" user "User.Eco1")
		(23 "Eco2.User" user "User.Eco2")
		(25 "Edge.Cuts" user "Board Geometry/Outline")
		(27 "Margin" user)
		(31 "F.CrtYd" user "Package Geometry/Place Bound Top")
		(29 "B.CrtYd" user "Package Geometry/Place Bound Bottom")
		(35 "F.Fab" user "Ref Des/Assembly Top")
		(33 "B.Fab" user "Ref Des/Assembly Bottom")
	)
	(footprint ""
		(layer "F.Cu")
		(at 390.474708 -409.15082 180)
		(property "Reference" "C7001"
			(at 8.527796 1.740408 0)
			(unlocked yes)
			(layer "F.SilkS")
			(effects
				(font
					(size 0.7874 0.5842)
					(thickness 0.1524)
				)
				(justify left)
			)
		)
		(property "Value" ""
			(at 0 0 180)
			(layer "F.Fab")
			(effects
				(font
					(size 1.27 1.27)
				)
			)
		)
		(duplicate_pad_numbers_are_jumpers no)
		(fp_line
			(start 4.53898 2.15011)
			(end -4.53898 2.15011)
			(stroke
				(width 0.1524)
				(type default)
			)
			(layer "F.SilkS")
		)
		(fp_line
			(start 4.53898 -2.15011)
			(end 4.53898 2.15011)
			(stroke
				(width 0.1524)
				(type default)
			)
			(layer "F.SilkS")
		)
		(fp_line
			(start -4.53898 2.15011)
			(end -4.53898 -2.15011)
			(stroke
				(width 0.1524)
				(type default)
			)
			(layer "F.SilkS")
		)
		(fp_line
			(start -4.53898 -2.15011)
			(end 4.53898 -2.15011)
			(stroke
				(width 0.1524)
				(type default)
			)
			(layer "F.SilkS")
		)
		(fp_line
			(start -4.53898 -2.150618)
			(end -4.539742 2.152142)
			(stroke
				(width 0.1524)
				(type default)
			)
			(layer "F.SilkS")
		)
		(fp_line
			(start -4.69138 -2.150618)
			(end -4.692396 2.161032)
			(stroke
				(width 0.1524)
				(type default)
			)
			(layer "F.SilkS")
		)
		(fp_line
			(start -4.83108 2.150364)
			(end -4.447794 2.149348)
			(stroke
				(width 0.1524)
				(type default)
			)
			(layer "F.SilkS")
		)
		(fp_line
			(start -4.84378 -2.150618)
			(end -4.53898 -2.150618)
			(stroke
				(width 0.1524)
				(type default)
			)
			(layer "F.SilkS")
		)
		(fp_line
			(start -4.84378 -2.150618)
			(end -4.842256 2.163064)
			(stroke
				(width 0.1524)
				(type default)
			)
			(layer "F.SilkS")
		)
		(fp_line
			(start 3.64998 2.15011)
			(end -3.64998 2.15011)
			(stroke
				(width 0.1)
				(type default)
			)
			(layer "F.Fab")
		)
		(fp_line
			(start 3.64998 -2.15011)
			(end 3.64998 2.15011)
			(stroke
				(width 0.1)
				(type default)
			)
			(layer "F.Fab")
		)
		(fp_line
			(start -3.64998 2.15011)
			(end -3.64998 -2.15011)
			(stroke
				(width 0.1)
				(type default)
			)
			(layer "F.Fab")
		)
		(fp_line
			(start -3.64998 -2.15011)
			(end 3.64998 -2.15011)
			(stroke
				(width 0.1)
				(type default)
			)
			(layer "F.Fab")
		)
		(fp_text user "-"
			(at 4.592574 -0.165608 180)
			(unlocked yes)
			(layer "F.SilkS")
			(effects
				(font
					(size 1.905 1.4224)
					(thickness 0.1524)
				)
				(justify left)
			)
		)
		(fp_text user "+"
			(at -6.024372 -1.571498 180)
			(unlocked yes)
			(layer "F.SilkS")
			(effects
				(font
					(size 1.905 1.4224)
					(thickness 0.1524)
				)
				(justify left)
			)
		)
		(fp_text user "-"
			(at 4.313174 -0.094488 180)
			(unlocked yes)
			(layer "F.Fab")
			(effects
				(font
					(size 1.905 1.4224)
					(thickness 0.1524)
				)
				(justify left)
			)
		)
		(fp_text user "+"
			(at -6.214872 -0.337058 180)
			(unlocked yes)
			(layer "F.Fab")
			(effects
				(font
					(size 1.905 1.4224)
					(thickness 0.1524)
				)
				(justify left)
			)
		)
		(pad "1" smd rect
			(at -3.199892 0 180)
			(size 2.413 2.8194)
			(layers "F.Cu" "F.Mask" "F.Paste")
			(net "P0V9_CPU0_RT_2D")
		)
		(pad "2" smd rect
			(at 3.199892 0 180)
			(size 2.413 2.8194)
			(layers "F.Cu" "F.Mask" "F.Paste")
			(net "GND")
		)
	)
	(footprint ""
		(layer "F.Cu")
		(at 110.856014 -258.795266)
		(property "Reference" "C2503"
			(at 0 0 0)
			(layer "F.SilkS")
			(hide yes)
			(effects
				(font
					(size 1.27 1.27)
				)
			)
		)
		(property "Value" ""
			(at 0 0 0)
			(layer "F.Fab")
			(effects
				(font
					(size 1.27 1.27)
				)
			)
		)
		(duplicate_pad_numbers_are_jumpers no)
		(fp_line
			(start -0.7874 -0.4064)
			(end 0.7874 -0.4064)
			(stroke
				(width 0.1524)
				(type default)
			)
			(layer "F.SilkS")
		)
		(fp_line
			(start -0.7874 0.4064)
			(end -0.7874 -0.4064)
			(stroke
				(width 0.1524)
				(type default)
			)
			(layer "F.SilkS")
		)
		(fp_line
			(start 0.7874 -0.4064)
			(end 0.7874 0.4064)
			(stroke
				(width 0.1524)
				(type default)
			)
			(layer "F.SilkS")
		)
		(fp_line
			(start 0.7874 0.4064)
			(end -0.7874 0.4064)
			(stroke
				(width 0.1524)
				(type default)
			)
			(layer "F.SilkS")
		)
		(fp_line
			(start -0.67945 -0.305054)
			(end -0.12065 -0.305054)
			(stroke
				(width 0.1)
				(type default)
			)
			(layer "F.Fab")
		)
		(fp_line
			(start -0.67945 0.3048)
			(end -0.67945 -0.305054)
			(stroke
				(width 0.1)
				(type default)
			)
			(layer "F.Fab")
		)
		(fp_line
			(start -0.12065 -0.305054)
			(end -0.12065 -0.2794)
			(stroke
				(width 0.1)
				(type default)
			)
			(layer "F.Fab")
		)
		(fp_line
			(start -0.12065 -0.2794)
			(end 0.12065 -0.2794)
			(stroke
				(width 0.1)
				(type default)
			)
			(layer "F.Fab")
		)
		(fp_line
			(start -0.12065 0.2794)
			(end -0.12065 0.3048)
			(stroke
				(width 0.1)
				(type default)
			)
			(layer "F.Fab")
		)
		(fp_line
			(start -0.12065 0.3048)
			(end -0.67945 0.3048)
			(stroke
				(width 0.1)
				(type default)
			)
			(layer "F.Fab")
		)
		(fp_line
			(start 0.120396 0.2794)
			(end -0.12065 0.2794)
			(stroke
				(width 0.1)
				(type default)
			)
			(layer "F.Fab")
		)
		(fp_line
			(start 0.120396 0.3048)
			(end 0.120396 0.2794)
			(stroke
				(width 0.1)
				(type default)
			)
			(layer "F.Fab")
		)
		(fp_line
			(start 0.12065 -0.3048)
			(end 0.67945 -0.3048)
			(stroke
				(width 0.1)
				(type default)
			)
			(layer "F.Fab")
		)
		(fp_line
			(start 0.12065 -0.2794)
			(end 0.12065 -0.3048)
			(stroke
				(width 0.1)
				(type default)
			)
			(layer "F.Fab")
		)
		(fp_line
			(start 0.67945 -0.3048)
			(end 0.67945 0.3048)
			(stroke
				(width 0.1)
				(type default)
			)
			(layer "F.Fab")
		)
		(fp_line
			(start 0.67945 0.3048)
			(end 0.120396 0.3048)
			(stroke
				(width 0.1)
				(type default)
			)
			(layer "F.Fab")
		)
		(pad "1" smd circle
			(at -0.40005 0)
			(size 0 0)
			(layers "F.Cu" "F.Mask" "F.Paste")
			(net "PVDD11_S3_P1")
		)
		(pad "2" smd circle
			(at 0.40005 0)
			(size 0 0)
			(layers "F.Cu" "F.Mask" "F.Paste")
			(net "GND")
		)
	)
	(footprint ""
		(layer "F.Cu")
		(at 322.147946 -416.899344 -90)
		(property "Reference" "C6514"
			(at 0 0 270)
			(layer "F.SilkS")
			(hide yes)
			(effects
				(font
					(size 1.27 1.27)
				)
			)
		)
		(property "Value" ""
			(at 0 0 270)
			(layer "F.Fab")
			(effects
				(font
					(size 1.27 1.27)
				)
			)
		)
		(duplicate_pad_numbers_are_jumpers no)
		(fp_line
			(start -0.299974 0.150114)
			(end -0.299974 -0.150114)
			(stroke
				(width 0.1)
				(type default)
			)
			(layer "F.Fab")
		)
		(fp_line
			(start 0.299974 0.150114)
			(end -0.299974 0.150114)
			(stroke
				(width 0.1)
				(type default)
			)
			(layer "F.Fab")
		)
		(fp_line
			(start -0.299974 -0.150114)
			(end 0.299974 -0.150114)
			(stroke
				(width 0.1)
				(type default)
			)
			(layer "F.Fab")
		)
		(fp_line
			(start 0.299974 -0.150114)
			(end 0.299974 0.150114)
			(stroke
				(width 0.1)
				(type default)
			)
			(layer "F.Fab")
		)
		(pad "1" smd rect
			(at -0.2667 0 270)
			(size 0.3048 0.381)
			(layers "F.Cu" "F.Mask" "F.Paste")
			(net "P5E_CPU0_P0_TX_BUF_C_DN<6>")
		)
		(pad "2" smd rect
			(at 0.2667 0 270)
			(size 0.3048 0.381)
			(layers "F.Cu" "F.Mask" "F.Paste")
			(net "P5E_CPU0_P0_TX_BUF_DN<6>")
		)
	)
)
